(kicad_pcb
	(version 20260206)
	(generator "pcbnew")
	(generator_version "10.0")
	(general
		(thickness 1.6)
		(legacy_teardrops no)
	)
	(paper "A4")
	(title_block
		(title "12092022_DA0F0TYB4D0_F0T_Panel_BD_Front_D_brd_v02_OCP.brd")
		(comment 1 "Grand Teton / footprints 126-128 of 128")
	)
	(layers
		(0 "F.Cu" signal "TOP")
		(4 "In1.Cu" signal "GND")
		(6 "In2.Cu" signal "GND1")
		(2 "B.Cu" signal "BOTTOM")
		(9 "F.Adhes" user "F.Adhesive")
		(11 "B.Adhes" user "B.Adhesive")
		(13 "F.Paste" user "Package Geometry/Pastemask Top")
		(15 "B.Paste" user "Package Geometry/Pastemask Bottom")
		(5 "F.SilkS" user "Ref Des/Silkscreen Top")
		(7 "B.SilkS" user "Ref Des/Silkscreen Bottom")
		(1 "F.Mask" user "Board Geometry/Soldermask Top")
		(3 "B.Mask" user "Board Geometry/Soldermask Bottom")
		(17 "Dwgs.User" user "User.Drawings")
		(19 "Cmts.User" user "User.Comments")
		(21 "Eco1.User" user "User.Eco1")
		(23 "Eco2.User" user "User.Eco2")
		(25 "Edge.Cuts" user "Board Geometry/Outline")
		(27 "Margin" user)
		(31 "F.CrtYd" user "Package Geometry/Place Bound Top")
		(29 "B.CrtYd" user "Package Geometry/Place Bound Bottom")
		(35 "F.Fab" user "Ref Des/Assembly Top")
		(33 "B.Fab" user "Ref Des/Assembly Bottom")
	)
	(footprint ""
		(layer "B.Cu")
		(at 4.318 -41.91)
		(property "Reference" "ME3"
			(at 0 0 0)
			(layer "B.SilkS")
			(hide yes)
			(effects
				(font
					(size 1.27 1.27)
				)
				(justify mirror)
			)
		)
		(property "Value" ""
			(at 0 0 0)
			(layer "B.Fab")
			(effects
				(font
					(size 1.27 1.27)
				)
				(justify mirror)
			)
		)
		(duplicate_pad_numbers_are_jumpers no)
	)
	(footprint ""
		(layer "B.Cu")
		(at 12.192 -40.64)
		(property "Reference" "ME2"
			(at 0 0 0)
			(layer "B.SilkS")
			(hide yes)
			(effects
				(font
					(size 1.27 1.27)
				)
				(justify mirror)
			)
		)
		(property "Value" ""
			(at 0 0 0)
			(layer "B.Fab")
			(effects
				(font
					(size 1.27 1.27)
				)
				(justify mirror)
			)
		)
		(duplicate_pad_numbers_are_jumpers no)
		(fp_poly
			(pts
				(xy -1.32715 -3.4417) (xy -2.01295 -3.4417) (xy -2.01295 -3.2512) (xy -1.32715 -3.2512)
			)
			(stroke
				(width 0)
				(type default)
			)
			(fill yes)
			(layer "B.SilkS")
		)
		(fp_poly
			(pts
				(xy 0 -0.5842) (xy -3.3401 -0.5842) (xy -3.3401 0) (xy 0 0)
			)
			(stroke
				(width 0)
				(type default)
			)
			(fill yes)
			(layer "B.SilkS")
		)
		(fp_poly
			(pts
				(xy 0.070612 -0.681228) (xy 0.197612 -0.820928) (xy -0.852678 -1.91262) (xy -0.728472 -3.29184)
				(xy 0.248412 -4.300728) (xy 0.184912 -4.478528) (xy 0.007112 -4.503928) (xy -0.684022 -3.785616)
				(xy -0.65659 -4.0894) (xy -0.97155 -4.3434) (xy -1.22555 -4.3561) (xy -1.46685 -4.4704) (xy -2.01295 -4.4704)
				(xy -2.15265 -4.4069) (xy -2.44475 -4.191) (xy -2.49555 -4.191) (xy -2.59715 -4.2926) (xy -2.80035 -4.2672)
				(xy -2.88925 -4.1656) (xy -2.88925 -4.029456) (xy -3.345688 -4.503928) (xy -3.523488 -4.478528)
				(xy -3.586988 -4.300728) (xy -2.88925 -3.58013) (xy -2.88925 -3.3147) (xy -2.82575 -3.2385) (xy -2.67335 -3.2385)
				(xy -2.521966 -1.875282) (xy -2.545842 -1.85039)
				(arc
					(start -2.55905 -1.8415)
					(mid -2.648099 -1.766068)
					(end -2.717292 -1.672082)
				)
				(xy -3.536188 -0.820928) (xy -3.409188 -0.681228) (xy -3.244088 -0.693928)
				(arc
					(start -2.737612 -1.216914)
					(mid -2.31728 -0.925553)
					(end -1.86055 -1.1557)
				)
				(xy -0.92075 -1.1557) (xy -0.888492 -1.51384) (xy -0.094488 -0.693928)
			)
			(stroke
				(width 0)
				(type default)
			)
			(fill yes)
			(layer "B.SilkS")
		)
	)
	(footprint ""
		(layer "B.Cu")
		(at 28.575 -77.089)
		(property "Reference" "ME4"
			(at 0 0 0)
			(layer "B.SilkS")
			(hide yes)
			(effects
				(font
					(size 1.27 1.27)
				)
				(justify mirror)
			)
		)
		(property "Value" ""
			(at 0 0 0)
			(layer "B.Fab")
			(effects
				(font
					(size 1.27 1.27)
				)
				(justify mirror)
			)
		)
		(duplicate_pad_numbers_are_jumpers no)
	)
)
